(kicad_pcb
	(version 20221018)
	(generator pcbnew)
	(general
    (thickness 1.518)
  )
	(paper "A4")
	(title_block
    (title "Kria K26 Devboard")
    (date "2024-03-26")
    (rev "1.2.5")
    (comment 1 "www.antmicro.com")
    (comment 2 "Antmicro Ltd.")
		(comment 9 "footprints 362-367 of 660")
	)
	(layers
    (0 "F.Cu" mixed)
    (1 "In1.Cu" power)
    (2 "In2.Cu" mixed)
    (3 "In3.Cu" power)
    (4 "In4.Cu" mixed)
    (5 "In5.Cu" power)
    (6 "In6.Cu" mixed)
    (31 "B.Cu" power)
    (32 "B.Adhes" user "B.Adhesive")
    (33 "F.Adhes" user "F.Adhesive")
    (34 "B.Paste" user)
    (35 "F.Paste" user)
    (36 "B.SilkS" user "B.Silkscreen")
    (37 "F.SilkS" user "F.Silkscreen")
    (38 "B.Mask" user)
    (39 "F.Mask" user)
    (40 "Dwgs.User" user "User.Drawings")
    (41 "Cmts.User" user "User.Comments")
    (42 "Eco1.User" user "User.Eco1")
    (43 "Eco2.User" user "User.Eco2")
    (44 "Edge.Cuts" user)
    (45 "Margin" user)
    (46 "B.CrtYd" user "B.Courtyard")
    (47 "F.CrtYd" user "F.Courtyard")
    (48 "B.Fab" user)
    (49 "F.Fab" user)
  )
	(footprint "kria-k26-devboard-footprints:Oscillator_SMD_ECS_2016MV_2x1.6x0.85mm" (layer "F.Cu")
    (at 127.25 93.28 180)
    (property "Author" "Antmicro")
    (property "License" "Apache-2.0")
    (property "MPN" "ECS-2016MV-250-CN-TR")
    (property "Manufacturer" "ECS Inc. International")
    (property "Sheetfile" "usb.kicad_sch")
    (property "Sheetname" "USB")
    (property "Val" "25 MHz")
    (property "ki_description" "Oscillator, 25 MHz, HCMOS, SMD, 2mm x 1.6mm, MultiVolt ECS-2016MV Series")
    (property "ki_keywords" "OSCILLATOR")
    (attr smd)
    (fp_text reference "Y4" (at -0.99 -0.4) (layer "F.SilkS")
        (effects (font (size 0.7 0.7) (thickness 0.15)) (justify left bottom))
    )
    (fp_text value "Oscillator_25MHz_ESC_2016MV" (at 0 2.2 180) (layer "F.Fab") hide
        (effects (font (size 0.7 0.7) (thickness 0.15)) (justify left bottom))
    )
    (fp_text user "Author: Antmicro" (at -1.05 4.6 180) (layer "F.Fab") hide
        (effects (font (size 0.7 0.7) (thickness 0.15)) (justify left bottom))
    )
    (fp_text user "${REFERENCE}" (at -1.05 3.4 180) (layer "F.Fab") hide
        (effects (font (size 0.7 0.7) (thickness 0.15)) (justify left bottom))
    )
    (fp_text user "License: Apache-2.0" (at -1.05 5.8 180) (layer "F.Fab") hide
        (effects (font (size 0.7 0.7) (thickness 0.15)) (justify left bottom))
    )
    (fp_line (start -0.95 0.4) (end -0.95 -0.4)
      (stroke (width 0.15) (type solid)) (layer "F.SilkS"))
    (fp_line (start -0.4 -1.15) (end 0.4 -1.15)
      (stroke (width 0.15) (type solid)) (layer "F.SilkS"))
    (fp_line (start -0.4 1.15) (end 0.4 1.15)
      (stroke (width 0.15) (type solid)) (layer "F.SilkS"))
    (fp_line (start 0.95 0.4) (end 0.95 -0.4)
      (stroke (width 0.15) (type solid)) (layer "F.SilkS"))
    (fp_circle (center -0.95 -1.15) (end -0.9 -1.15)
      (stroke (width 0.15) (type solid)) (fill solid) (layer "F.SilkS"))
    (fp_rect (start -1.05 -1.25) (end 1.05 1.24)
      (stroke (width 0.05) (type solid)) (fill none) (layer "F.CrtYd"))
    (fp_rect (start -0.85 -1.054) (end 0.852 1.054)
      (stroke (width 0.15) (type solid)) (fill none) (layer "F.Fab"))
    (pad "1" smd rect (at -0.486 -0.637 180) (size 0.6858 0.7874) (layers "F.Cu" "F.Paste" "F.Mask")
      (net 798 "unconnected-(Y4-EN-Pad1)") (pinfunction "EN") (pintype "input+no_connect"))
    (pad "2" smd rect (at -0.486 0.636 180) (size 0.6858 0.7874) (layers "F.Cu" "F.Paste" "F.Mask")
      (net 1 "GND") (pinfunction "GND") (pintype "power_in"))
    (pad "3" smd rect (at 0.487 0.636 180) (size 0.6858 0.7874) (layers "F.Cu" "F.Paste" "F.Mask")
      (net 294 "/USB/CLK_IN") (pinfunction "OUT") (pintype "output"))
    (pad "4" smd rect (at 0.487 -0.637 180) (size 0.6858 0.7874) (layers "F.Cu" "F.Paste" "F.Mask")
      (net 15 "PS_3V3") (pinfunction "VDD") (pintype "power_in"))
  )
	(footprint "kria-k26-devboard-footprints:SOT-416" (layer "F.Cu")
    (at 151.2 67.79 180)
    (descr "SOT-416")
    (tags "SOT-416")
    (property "Author" "Antmicro")
    (property "License" "Apache-2.0")
    (property "MPN" "DTC014TEBTL")
    (property "Manufacturer" "ROHM Semiconductor")
    (property "Sheetfile" "usbc-socket.kicad_sch")
    (property "Sheetname" "USB-C socket")
    (property "ki_description" "Digital NPN Transistor, 10k/NONE, EMT-3")
    (attr smd)
    (fp_text reference "Q17" (at 1.6 -1.94 180) (layer "F.SilkS")
        (effects (font (size 0.7 0.7) (thickness 0.15)) (justify left bottom))
    )
    (fp_text value "DTC014T_SOT-416" (at 0 2 180) (layer "F.Fab") hide
        (effects (font (size 0.7 0.7) (thickness 0.15)) (justify left bottom))
    )
    (fp_text user "License: Apache-2.0" (at -1 5.802 180) (layer "F.Fab") hide
        (effects (font (size 0.7 0.7) (thickness 0.15)) (justify left bottom))
    )
    (fp_text user "${REFERENCE}" (at -1 3.4 180) (layer "F.Fab") hide
        (effects (font (size 0.7 0.7) (thickness 0.15)) (justify left bottom))
    )
    (fp_text user "Author: Antmicro" (at -1 4.602 180) (layer "F.Fab") hide
        (effects (font (size 0.7 0.7) (thickness 0.15)) (justify left bottom))
    )
    (fp_line (start -0.5 -0.15) (end -0.5 0.15)
      (stroke (width 0.15) (type solid)) (layer "F.SilkS"))
    (fp_line (start 0.5 0.9) (end -0.5 0.9)
      (stroke (width 0.15) (type solid)) (layer "F.SilkS"))
    (fp_line (start 0.5 0.9) (end 0.5 0.7)
      (stroke (width 0.15) (type solid)) (layer "F.SilkS"))
    (fp_line (start 0.508 -0.9) (end -0.5 -0.9)
      (stroke (width 0.15) (type solid)) (layer "F.SilkS"))
    (fp_line (start 0.508 -0.9) (end 0.508 -0.592)
      (stroke (width 0.15) (type solid)) (layer "F.SilkS"))
    (fp_rect (start -1 -1.05) (end 1 1.05)
      (stroke (width 0.05) (type solid)) (fill none) (layer "F.CrtYd"))
    (fp_line (start -0.05 -0.9) (end -0.45 -0.5)
      (stroke (width 0.15) (type solid)) (layer "F.Fab"))
    (fp_rect (start 0.45 0.9) (end -0.45 -0.9)
      (stroke (width 0.15) (type solid)) (fill none) (layer "F.Fab"))
    (pad "1" smd rect (at -0.652 -0.5 180) (size 0.6 0.5) (layers "F.Cu" "F.Paste" "F.Mask")
      (net 229 "/Debug and JTAG/PD_EN") (pinfunction "B") (pintype "input"))
    (pad "2" smd rect (at -0.652 0.498 180) (size 0.6 0.5) (layers "F.Cu" "F.Paste" "F.Mask")
      (net 1 "GND") (pinfunction "E") (pintype "passive"))
    (pad "3" smd rect (at 0.65 0 180) (size 0.6 0.5) (layers "F.Cu" "F.Paste" "F.Mask")
      (net 433 "Net-(Q16-G)") (pinfunction "C") (pintype "passive"))
  )
	(footprint "kria-k26-devboard-footprints:C_0402_1005Metric" (layer "F.Cu")
    (at 91.535 140.61 -90)
    (descr "Capacitor SMD 0402")
    (tags "capacitor SMD 0402")
    (property "Author" "Antmicro")
    (property "Dielectric" "X5R")
    (property "License" "Apache-2.0")
    (property "MPN" "GRM155R61H104KE14D")
    (property "Manufacturer" "Murata")
    (property "Sheetfile" "k26_som.kicad_sch")
    (property "Sheetname" "Xilinx K26 SOM")
    (property "Val" "100n")
    (property "Voltage" "50V")
    (property "ki_description" " ")
    (attr smd)
    (fp_text reference "C124" (at -0.92 -3.605 -90) (layer "F.SilkS")
        (effects (font (size 0.7 0.7) (thickness 0.15)) (justify left bottom))
    )
    (fp_text value "C_100n_0402" (at 0 1.4 -90) (layer "F.Fab") hide
        (effects (font (size 0.7 0.7) (thickness 0.15)) (justify left bottom))
    )
    (fp_text user "${REFERENCE}" (at -0.932 3.168 -90) (layer "F.Fab") hide
        (effects (font (size 0.7 0.7) (thickness 0.15)) (justify left bottom))
    )
    (fp_text user "Author: Antmicro" (at -0.932 4.17 -90) (layer "F.Fab") hide
        (effects (font (size 0.7 0.7) (thickness 0.15)) (justify left bottom))
    )
    (fp_text user "License: Apache-2.0" (at -0.932 5.17 -90) (layer "F.Fab") hide
        (effects (font (size 0.7 0.7) (thickness 0.15)) (justify left bottom))
    )
    (fp_rect (start -0.94 -0.47) (end 0.94 0.47)
      (stroke (width 0.05) (type solid)) (fill none) (layer "F.CrtYd"))
    (fp_rect (start -0.499 -0.249) (end 0.499 0.249)
      (stroke (width 0.15) (type solid)) (fill none) (layer "F.Fab"))
    (pad "1" smd roundrect (at -0.484 0 270) (size 0.59 0.64) (layers "F.Cu" "F.Paste" "F.Mask") (roundrect_rratio 0.25)
      (net 21 "PL_1V2") (pintype "passive"))
    (pad "2" smd roundrect (at 0.484 0 270) (size 0.59 0.64) (layers "F.Cu" "F.Paste" "F.Mask") (roundrect_rratio 0.25)
      (net 1 "GND") (pintype "passive"))
  )
	(footprint "kria-k26-devboard-footprints:C_0402_1005Metric" (layer "F.Cu")
    (at 93.43 140.61 -90)
    (descr "Capacitor SMD 0402")
    (tags "capacitor SMD 0402")
    (property "Author" "Antmicro")
    (property "Dielectric" "")
    (property "License" "Apache-2.0")
    (property "MPN" "GRM155R61A475MEAAD")
    (property "Manufacturer" "Murata")
    (property "Sheetfile" "k26_som.kicad_sch")
    (property "Sheetname" "Xilinx K26 SOM")
    (property "Val" "4u7")
    (property "Voltage" "")
    (property "ki_description" " ")
    (attr smd)
    (fp_text reference "C123" (at -0.92 -3.605 -90) (layer "F.SilkS")
        (effects (font (size 0.7 0.7) (thickness 0.15)) (justify left bottom))
    )
    (fp_text value "C_4u7_0402" (at 0 1.4 -90) (layer "F.Fab") hide
        (effects (font (size 0.7 0.7) (thickness 0.15)) (justify left bottom))
    )
    (fp_text user "Author: Antmicro" (at -0.932 4.17 -90) (layer "F.Fab") hide
        (effects (font (size 0.7 0.7) (thickness 0.15)) (justify left bottom))
    )
    (fp_text user "${REFERENCE}" (at -0.932 3.168 -90) (layer "F.Fab") hide
        (effects (font (size 0.7 0.7) (thickness 0.15)) (justify left bottom))
    )
    (fp_text user "License: Apache-2.0" (at -0.932 5.17 -90) (layer "F.Fab") hide
        (effects (font (size 0.7 0.7) (thickness 0.15)) (justify left bottom))
    )
    (fp_rect (start -0.94 -0.47) (end 0.94 0.47)
      (stroke (width 0.05) (type solid)) (fill none) (layer "F.CrtYd"))
    (fp_rect (start -0.499 -0.249) (end 0.499 0.249)
      (stroke (width 0.15) (type solid)) (fill none) (layer "F.Fab"))
    (pad "1" smd roundrect (at -0.484 0 270) (size 0.59 0.64) (layers "F.Cu" "F.Paste" "F.Mask") (roundrect_rratio 0.25)
      (net 21 "PL_1V2") (pintype "passive"))
    (pad "2" smd roundrect (at 0.484 0 270) (size 0.59 0.64) (layers "F.Cu" "F.Paste" "F.Mask") (roundrect_rratio 0.25)
      (net 1 "GND") (pintype "passive"))
  )
	(footprint "kria-k26-devboard-footprints:C_0402_1005Metric" (layer "F.Cu")
    (at 92.48 140.61 -90)
    (descr "Capacitor SMD 0402")
    (tags "capacitor SMD 0402")
    (property "Author" "Antmicro")
    (property "Dielectric" "X5R")
    (property "License" "Apache-2.0")
    (property "MPN" "GRM155R61H104KE14D")
    (property "Manufacturer" "Murata")
    (property "Sheetfile" "k26_som.kicad_sch")
    (property "Sheetname" "Xilinx K26 SOM")
    (property "Val" "100n")
    (property "Voltage" "50V")
    (property "ki_description" " ")
    (attr smd)
    (fp_text reference "C125" (at -0.92 -3.605 -90) (layer "F.SilkS")
        (effects (font (size 0.7 0.7) (thickness 0.15)) (justify left bottom))
    )
    (fp_text value "C_100n_0402" (at 0 1.4 -90) (layer "F.Fab") hide
        (effects (font (size 0.7 0.7) (thickness 0.15)) (justify left bottom))
    )
    (fp_text user "Author: Antmicro" (at -0.932 4.17 -90) (layer "F.Fab") hide
        (effects (font (size 0.7 0.7) (thickness 0.15)) (justify left bottom))
    )
    (fp_text user "License: Apache-2.0" (at -0.932 5.17 -90) (layer "F.Fab") hide
        (effects (font (size 0.7 0.7) (thickness 0.15)) (justify left bottom))
    )
    (fp_text user "${REFERENCE}" (at -0.932 3.168 -90) (layer "F.Fab") hide
        (effects (font (size 0.7 0.7) (thickness 0.15)) (justify left bottom))
    )
    (fp_rect (start -0.94 -0.47) (end 0.94 0.47)
      (stroke (width 0.05) (type solid)) (fill none) (layer "F.CrtYd"))
    (fp_rect (start -0.499 -0.249) (end 0.499 0.249)
      (stroke (width 0.15) (type solid)) (fill none) (layer "F.Fab"))
    (pad "1" smd roundrect (at -0.484 0 270) (size 0.59 0.64) (layers "F.Cu" "F.Paste" "F.Mask") (roundrect_rratio 0.25)
      (net 21 "PL_1V2") (pintype "passive"))
    (pad "2" smd roundrect (at 0.484 0 270) (size 0.59 0.64) (layers "F.Cu" "F.Paste" "F.Mask") (roundrect_rratio 0.25)
      (net 1 "GND") (pintype "passive"))
  )
	(footprint "kria-k26-devboard-footprints:DFN-14-1EP_4x3mm_P0.5mm" (layer "F.Cu")
    (at 187.975 64.75)
    (property "Author" "Antmicro")
    (property "License" "Apache-2.0")
    (property "MPN" "LTC4358CDE#PBF")
    (property "Manufacturer" "Analog Devices")
    (property "Sheetfile" "supply-oring.kicad_sch")
    (property "Sheetname" "Supply ORing")
    (property "ki_description" "Ideal diode")
    (property "ki_keywords" "SMT, PMIC, IC, POWER, MANAGEMENT, DIODE, CONTROLLER")
    (attr smd)
    (fp_text reference "U58" (at -2.195 2.51 90) (layer "F.SilkS")
        (effects (font (size 0.7 0.7) (thickness 0.15)) (justify left bottom))
    )
    (fp_text value "LTC4358CDE" (at 0 3.2) (layer "F.Fab") hide
        (effects (font (size 0.7 0.7) (thickness 0.15)) (justify left bottom))
    )
    (fp_text user "License: Apache-2.0" (at -0.659 8.198) (layer "F.Fab") hide
        (effects (font (size 0.7 0.7) (thickness 0.15)) (justify left bottom))
    )
    (fp_text user "Author: Antmicro" (at -0.659 6.998) (layer "F.Fab") hide
        (effects (font (size 0.7 0.7) (thickness 0.15)) (justify left bottom))
    )
    (fp_text user "${REFERENCE}" (at -0.659 5.797) (layer "F.Fab") hide
        (effects (font (size 0.7 0.7) (thickness 0.15)) (justify left bottom))
    )
    (fp_line (start -1.6 -2.045) (end 1.5995 -2.045)
      (stroke (width 0.15) (type solid)) (layer "F.SilkS"))
    (fp_line (start -1.6 2.044) (end 1.6 2.044)
      (stroke (width 0.15) (type solid)) (layer "F.SilkS"))
    (fp_circle (center -1.85 -1.9) (end -1.8 -1.9)
      (stroke (width 0.15) (type solid)) (fill solid) (layer "F.SilkS"))
    (fp_line (start -2.1 -1.87) (end -1.79 -1.87)
      (stroke (width 0.05) (type solid)) (layer "F.CrtYd"))
    (fp_line (start -2.1 1.9) (end -2.1 -1.87)
      (stroke (width 0.05) (type solid)) (layer "F.CrtYd"))
    (fp_line (start -1.79 -2.28) (end 1.81 -2.28)
      (stroke (width 0.05) (type solid)) (layer "F.CrtYd"))
    (fp_line (start -1.79 -1.87) (end -1.79 -2.28)
      (stroke (width 0.05) (type solid)) (layer "F.CrtYd"))
    (fp_line (start -1.79 1.9) (end -2.1 1.9)
      (stroke (width 0.05) (type solid)) (layer "F.CrtYd"))
    (fp_line (start -1.79 2.31) (end -1.79 1.9)
      (stroke (width 0.05) (type solid)) (layer "F.CrtYd"))
    (fp_line (start 1.81 -2.28) (end 1.81 -1.87)
      (stroke (width 0.05) (type solid)) (layer "F.CrtYd"))
    (fp_line (start 1.81 1.9) (end 1.81 2.31)
      (stroke (width 0.05) (type solid)) (layer "F.CrtYd"))
    (fp_line (start 1.81 2.31) (end -1.79 2.31)
      (stroke (width 0.05) (type solid)) (layer "F.CrtYd"))
    (fp_line (start 2.1 -1.87) (end 1.81 -1.87)
      (stroke (width 0.05) (type solid)) (layer "F.CrtYd"))
    (fp_line (start 2.1 -1.87) (end 2.1 1.9)
      (stroke (width 0.05) (type solid)) (layer "F.CrtYd"))
    (fp_line (start 2.1 1.9) (end 1.81 1.9)
      (stroke (width 0.05) (type solid)) (layer "F.CrtYd"))
    (fp_line (start -1.55 -2.045) (end -1.55 2.044)
      (stroke (width 0.15) (type solid)) (layer "F.Fab"))
    (fp_line (start -1.55 2.044) (end 1.549 2.044)
      (stroke (width 0.15) (type solid)) (layer "F.Fab"))
    (fp_line (start 1.549 -2.045) (end -1.55 -2.045)
      (stroke (width 0.15) (type solid)) (layer "F.Fab"))
    (fp_line (start 1.549 2.044) (end 1.549 -2.045)
      (stroke (width 0.15) (type solid)) (layer "F.Fab"))
    (pad "" smd roundrect (at 0 -0.8) (size 1.3 1.3) (layers "F.Paste") (roundrect_rratio 0.05))
    (pad "" smd roundrect (at 0 0.8) (size 1.3 1.3) (layers "F.Paste") (roundrect_rratio 0.05))
    (pad "1" smd roundrect (at -1.445 -1.499) (size 0.807999 0.2548) (layers "F.Cu" "F.Paste" "F.Mask") (roundrect_rratio 0.25)
      (net 22 "/Power Supply/DC Input/DC_IN") (pinfunction "IN") (pintype "input"))
    (pad "2" smd roundrect (at -1.445 -1.001) (size 0.807999 0.2548) (layers "F.Cu" "F.Paste" "F.Mask") (roundrect_rratio 0.25)
      (net 22 "/Power Supply/DC Input/DC_IN") (pinfunction "IN") (pintype "passive"))
    (pad "3" smd roundrect (at -1.445 -0.5) (size 0.807999 0.2548) (layers "F.Cu" "F.Paste" "F.Mask") (roundrect_rratio 0.25)
      (net 22 "/Power Supply/DC Input/DC_IN") (pinfunction "IN") (pintype "passive"))
    (pad "4" smd roundrect (at -1.445 0) (size 0.807999 0.2548) (layers "F.Cu" "F.Paste" "F.Mask") (roundrect_rratio 0.25)
      (net 22 "/Power Supply/DC Input/DC_IN") (pinfunction "IN") (pintype "passive"))
    (pad "5" smd roundrect (at -1.445 0.5) (size 0.807999 0.2548) (layers "F.Cu" "F.Paste" "F.Mask") (roundrect_rratio 0.25)
      (net 791 "unconnected-(U58-GATE-Pad5)") (pinfunction "GATE") (pintype "output+no_connect"))
    (pad "6" smd roundrect (at -1.445 1) (size 0.807999 0.2548) (layers "F.Cu" "F.Paste" "F.Mask") (roundrect_rratio 0.25)
      (net 792 "unconnected-(U58-NC-Pad6)") (pinfunction "NC") (pintype "no_connect"))
    (pad "7" smd roundrect (at -1.445 1.5) (size 0.807999 0.2548) (layers "F.Cu" "F.Paste" "F.Mask") (roundrect_rratio 0.25)
      (net 331 "Net-(U58-GND)") (pinfunction "GND") (pintype "power_in"))
    (pad "8" smd roundrect (at 1.445 1.5) (size 0.807999 0.2548) (layers "F.Cu" "F.Paste" "F.Mask") (roundrect_rratio 0.25)
      (net 328 "Net-(U58-VDD)") (pinfunction "VDD") (pintype "passive"))
    (pad "9" smd roundrect (at 1.445 1) (size 0.807999 0.2548) (layers "F.Cu" "F.Paste" "F.Mask") (roundrect_rratio 0.25)
      (net 14 "/Power Supply/DC/DC conventers/DC_MAIN_BUS") (pinfunction "OUT") (pintype "passive"))
    (pad "10" smd roundrect (at 1.445 0.5) (size 0.807999 0.2548) (layers "F.Cu" "F.Paste" "F.Mask") (roundrect_rratio 0.25)
      (net 793 "unconnected-(U58-NC-Pad10)") (pinfunction "NC") (pintype "no_connect"))
    (pad "11" smd roundrect (at 1.445 0) (size 0.807999 0.2548) (layers "F.Cu" "F.Paste" "F.Mask") (roundrect_rratio 0.25)
      (net 22 "/Power Supply/DC Input/DC_IN") (pinfunction "IN") (pintype "passive"))
    (pad "12" smd roundrect (at 1.445 -0.501) (size 0.807999 0.2548) (layers "F.Cu" "F.Paste" "F.Mask") (roundrect_rratio 0.25)
      (net 22 "/Power Supply/DC Input/DC_IN") (pinfunction "IN") (pintype "passive"))
    (pad "13" smd roundrect (at 1.445 -1.001) (size 0.807999 0.2548) (layers "F.Cu" "F.Paste" "F.Mask") (roundrect_rratio 0.25)
      (net 22 "/Power Supply/DC Input/DC_IN") (pinfunction "IN") (pintype "passive"))
    (pad "14" smd roundrect (at 1.445 -1.499) (size 0.807999 0.2548) (layers "F.Cu" "F.Paste" "F.Mask") (roundrect_rratio 0.25)
      (net 22 "/Power Supply/DC Input/DC_IN") (pinfunction "IN") (pintype "passive"))
    (pad "15" smd roundrect (at 0 0) (size 1.8034 3.4036) (layers "F.Cu" "F.Mask") (roundrect_rratio 0.05)
      (net 14 "/Power Supply/DC/DC conventers/DC_MAIN_BUS") (pinfunction "DRAIN") (pintype "passive"))
  )
)
